(kicad_pcb
	(version 20260206)
	(generator "pcbnew")
	(generator_version "10.0")
	(general
		(thickness 1.21888)
		(legacy_teardrops no)
	)
	(paper "A4")
	(title_block
		(title "timecard-v9 — TimeCard-DC-V9_EXP.PcbDoc")
		(comment 1 "Time Appliance Project (Time Card) / footprints 178-186 of 402")
	)
	(layers
		(0 "F.Cu" signal "TOP")
		(4 "In1.Cu" signal "SGND")
		(6 "In2.Cu" signal "IN1")
		(8 "In3.Cu" signal "IN2")
		(10 "In4.Cu" signal "SGND1")
		(2 "B.Cu" signal "BOTTOM")
		(9 "F.Adhes" user "F.Adhesive")
		(11 "B.Adhes" user "B.Adhesive")
		(13 "F.Paste" user "Top Paste")
		(15 "B.Paste" user "Bottom Paste")
		(5 "F.SilkS" user "Top Overlay")
		(7 "B.SilkS" user "Bottom Overlay")
		(1 "F.Mask" user "Top Solder")
		(3 "B.Mask" user "Bottom Solder")
		(17 "Dwgs.User" user "User.Drawings")
		(19 "Cmts.User" user "User.Comments")
		(21 "Eco1.User" user "User.Eco1")
		(23 "Eco2.User" user "User.Eco2")
		(25 "Edge.Cuts" user)
		(27 "Margin" user)
		(31 "F.CrtYd" user "Top Courtyard")
		(29 "B.CrtYd" user "Bottom Courtyard")
		(35 "F.Fab" user "Top Component Center")
		(33 "B.Fab" user "Bottom Component Center")
	)
	(footprint "SamacSys:SOP50P310X90-8N"
		(layer "F.Cu")
		(at 77.42159 128.5162 180)
		(property "Reference" "U11"
			(at -0.303605 1.973069 0)
			(unlocked yes)
			(layer "F.SilkS")
			(effects
				(font
					(size 0.762 0.762)
					(thickness 0.2286)
				)
			)
		)
		(property "Value" "NC7WV125K8X"
			(at 6.207715 2.884671 180)
			(unlocked yes)
			(layer "F.SilkS")
			(hide yes)
			(effects
				(font
					(size 0.762 0.762)
					(thickness 0.2286)
				)
			)
		)
		(sheetname "01-USER_IO")
		(sheetfile "01-USER_IO.kicad_sch")
		(duplicate_pad_numbers_are_jumpers no)
		(fp_line
			(start 0.8 1)
			(end -0.8 1)
			(stroke
				(width 0.2)
				(type solid)
			)
			(layer "F.SilkS")
		)
		(fp_line
			(start 0.8 -1)
			(end 0.8 1)
			(stroke
				(width 0.2)
				(type solid)
			)
			(layer "F.SilkS")
		)
		(fp_line
			(start 0.8 -1)
			(end -0.8 -1)
			(stroke
				(width 0.2)
				(type solid)
			)
			(layer "F.SilkS")
		)
		(fp_line
			(start -0.8 -1)
			(end -0.8 1)
			(stroke
				(width 0.2)
				(type solid)
			)
			(layer "F.SilkS")
		)
		(fp_line
			(start -1.15 -1.25)
			(end -2 -1.25)
			(stroke
				(width 0.2)
				(type solid)
			)
			(layer "F.SilkS")
		)
		(pad "1" smd rect
			(at -1.575 -0.75 180)
			(size 0.85 0.3)
			(layers "F.Cu" "F.Mask" "F.Paste")
			(net "ANT3_IO_OUT")
		)
		(pad "2" smd rect
			(at -1.575 -0.25 180)
			(size 0.85 0.3)
			(layers "F.Cu" "F.Mask" "F.Paste")
			(net "ANT3_OUT")
		)
		(pad "3" smd rect
			(at -1.575 0.25 180)
			(size 0.85 0.3)
			(layers "F.Cu" "F.Mask" "F.Paste")
			(net "ANT3_IN")
		)
		(pad "4" smd rect
			(at -1.575 0.75 180)
			(size 0.85 0.3)
			(layers "F.Cu" "F.Mask" "F.Paste")
			(net "GND")
		)
		(pad "5" smd rect
			(at 1.575 0.75 180)
			(size 0.85 0.3)
			(layers "F.Cu" "F.Mask" "F.Paste")
			(net "NetR28_1")
		)
		(pad "6" smd rect
			(at 1.575 0.25 180)
			(size 0.85 0.3)
			(layers "F.Cu" "F.Mask" "F.Paste")
			(net "NetR28_1")
		)
		(pad "7" smd rect
			(at 1.575 -0.25 180)
			(size 0.85 0.3)
			(layers "F.Cu" "F.Mask" "F.Paste")
			(net "ANT3_IO_IN")
		)
		(pad "8" smd rect
			(at 1.575 -0.75 180)
			(size 0.85 0.3)
			(layers "F.Cu" "F.Mask" "F.Paste")
			(net "+3.3V")
		)
	)
	(footprint "Resistors:RESC2012X50N"
		(layer "F.Cu")
		(at 195.40761 145.69763)
		(property "Reference" "R19"
			(at -1.28527 -1.268085 0)
			(unlocked yes)
			(layer "F.SilkS")
			(effects
				(font
					(size 0.762 0.762)
					(thickness 0.2286)
				)
				(justify left bottom)
			)
		)
		(property "Value" "CRCW080533R0FKEA"
			(at -3.02491 -6.429165 0)
			(unlocked yes)
			(layer "F.SilkS")
			(hide yes)
			(effects
				(font
					(size 0.762 0.762)
					(thickness 0.2286)
				)
				(justify left bottom)
			)
		)
		(sheetname "04-PCIe_JTAG")
		(sheetfile "04-PCIe_JTAG.kicad_sch")
		(duplicate_pad_numbers_are_jumpers no)
		(fp_line
			(start 0 0.762)
			(end 0 -0.762)
			(stroke
				(width 0.1524)
				(type solid)
			)
			(layer "F.SilkS")
		)
		(pad "1" smd rect
			(at -1 0 90)
			(size 1.45 0.95)
			(layers "F.Cu" "F.Mask" "F.Paste")
			(net "FPGA_TDO")
		)
		(pad "2" smd rect
			(at 1 0 90)
			(size 1.45 0.95)
			(layers "F.Cu" "F.Mask" "F.Paste")
			(net "NetP4_3")
		)
	)
	(footprint "Passives:SOT65P210X110-3N"
		(layer "F.Cu")
		(at 200.9416 145.61546)
		(property "Reference" "D8"
			(at -0.22 -1.605915 0)
			(unlocked yes)
			(layer "F.SilkS")
			(effects
				(font
					(size 0.762 0.762)
					(thickness 0.2286)
				)
				(justify left bottom)
			)
		)
		(property "Value" "BAT54SW"
			(at 3.33084 8.222185 0)
			(unlocked yes)
			(layer "F.SilkS")
			(hide yes)
			(effects
				(font
					(size 0.762 0.762)
					(thickness 0.2286)
				)
				(justify left bottom)
			)
		)
		(sheetname "04-PCIe_JTAG")
		(sheetfile "04-PCIe_JTAG.kicad_sch")
		(duplicate_pad_numbers_are_jumpers no)
		(fp_line
			(start -0.325 -1.1)
			(end 0.675 -1.1)
			(stroke
				(width 0.2)
				(type solid)
			)
			(layer "F.SilkS")
		)
		(fp_line
			(start -0.325 1.09999)
			(end 0.675 1.09999)
			(stroke
				(width 0.2)
				(type solid)
			)
			(layer "F.SilkS")
		)
		(fp_line
			(start 0.675 -0.65)
			(end 0.675 -1.1)
			(stroke
				(width 0.2)
				(type solid)
			)
			(layer "F.SilkS")
		)
		(fp_line
			(start 0.675 1.09999)
			(end 0.675 0.65)
			(stroke
				(width 0.2)
				(type solid)
			)
			(layer "F.SilkS")
		)
		(fp_circle
			(center -1.125 -1.45001)
			(end -1.125 -1.57501)
			(stroke
				(width 0.25)
				(type solid)
			)
			(fill no)
			(layer "F.SilkS")
		)
		(pad "1" smd rect
			(at -1.125 -0.65 90)
			(size 0.5 0.9)
			(layers "F.Cu" "F.Mask" "F.Paste")
			(net "GND")
		)
		(pad "2" smd rect
			(at -1.125 0.65 90)
			(size 0.5 0.9)
			(layers "F.Cu" "F.Mask" "F.Paste")
			(net "+3.3V")
		)
		(pad "3" smd rect
			(at 1.125 0 90)
			(size 0.5 0.9)
			(layers "F.Cu" "F.Mask" "F.Paste")
			(net "FPGA_TDI")
		)
	)
	(footprint "Vault:FP-711AT-MFG"
		(layer "F.Cu")
		(at 113.1216 80.91363)
		(property "Reference" "U25"
			(at -0.2968 -1.570509 0)
			(unlocked yes)
			(layer "F.SilkS")
			(effects
				(font
					(size 0.762 0.762)
					(thickness 0.2032)
				)
			)
		)
		(property "Value" "NCP176AMX330TCG"
			(at 10.016735 2.579871 0)
			(unlocked yes)
			(layer "F.SilkS")
			(hide yes)
			(effects
				(font
					(size 0.762 0.762)
					(thickness 0.2032)
				)
			)
		)
		(sheetname "05-GPS_IMU_SENSORS")
		(sheetfile "05-GPS_IMU_SENSORS.kicad_sch")
		(duplicate_pad_numbers_are_jumpers no)
		(fp_line
			(start -0.625 -0.925)
			(end 0.625 -0.925)
			(stroke
				(width 0.2)
				(type solid)
			)
			(layer "F.SilkS")
		)
		(fp_line
			(start -0.615 0.925)
			(end 0.635 0.925)
			(stroke
				(width 0.2)
				(type solid)
			)
			(layer "F.SilkS")
		)
		(fp_circle
			(center -1.225 -0.4)
			(end -1.225 -0.525)
			(stroke
				(width 0.25)
				(type solid)
			)
			(fill no)
			(layer "F.SilkS")
		)
		(fp_line
			(start -0.8 -0.725)
			(end 0.8 -0.725)
			(stroke
				(width 0.2)
				(type solid)
			)
			(layer "F.CrtYd")
		)
		(fp_line
			(start -0.8 0.725)
			(end -0.8 -0.725)
			(stroke
				(width 0.2)
				(type solid)
			)
			(layer "F.CrtYd")
		)
		(fp_line
			(start -0.8 0.725)
			(end 0.8 0.725)
			(stroke
				(width 0.2)
				(type solid)
			)
			(layer "F.CrtYd")
		)
		(fp_line
			(start 0.8 0.725)
			(end 0.8 -0.725)
			(stroke
				(width 0.2)
				(type solid)
			)
			(layer "F.CrtYd")
		)
		(fp_line
			(start -0.8 -0.725)
			(end 0.8 -0.725)
			(stroke
				(width 0.2)
				(type solid)
			)
			(layer "F.Fab")
		)
		(fp_line
			(start -0.8 0.725)
			(end -0.8 -0.725)
			(stroke
				(width 0.2)
				(type solid)
			)
			(layer "F.Fab")
		)
		(fp_line
			(start -0.8 0.725)
			(end 0.8 0.725)
			(stroke
				(width 0.2)
				(type solid)
			)
			(layer "F.Fab")
		)
		(fp_line
			(start -0.5 0)
			(end 0.5 0)
			(stroke
				(width 0.1)
				(type solid)
			)
			(layer "F.Fab")
		)
		(fp_line
			(start 0 0.49999)
			(end 0 -0.5)
			(stroke
				(width 0.1)
				(type solid)
			)
			(layer "F.Fab")
		)
		(fp_line
			(start 0.8 0.725)
			(end 0.8 -0.725)
			(stroke
				(width 0.2)
				(type solid)
			)
			(layer "F.Fab")
		)
		(fp_text user "${REFERENCE}"
			(at 0 0.28425 0)
			(unlocked yes)
			(layer "F.Fab")
			(effects
				(font
					(face "Arial")
					(size 0.63 0.63)
					(thickness 0.1)
				)
				(justify left bottom)
			)
		)
		(pad "1" smd rect
			(at -0.515 -0.4)
			(size 0.37 0.24)
			(layers "F.Cu" "F.Mask" "F.Paste")
			(net "BNO_P3V3")
			(solder_mask_margin 0)
			(solder_paste_margin 0)
		)
		(pad "2" smd rect
			(at -0.515 0)
			(size 0.37 0.24)
			(layers "F.Cu" "F.Mask" "F.Paste")
			(net "BNO_P3V3")
			(solder_mask_margin 0)
			(solder_paste_margin 0)
		)
		(pad "3" smd rect
			(at -0.515 0.39999)
			(size 0.37 0.24)
			(layers "F.Cu" "F.Mask" "F.Paste")
			(net "GND")
			(solder_mask_margin 0)
			(solder_paste_margin 0)
		)
		(pad "4" smd rect
			(at 0.515 0.39999)
			(size 0.37 0.24)
			(layers "F.Cu" "F.Mask" "F.Paste")
			(net "+5.0V")
			(solder_mask_margin 0)
			(solder_paste_margin 0)
		)
		(pad "5" smd rect
			(at 0.515 0)
			(size 0.37 0.24)
			(layers "F.Cu" "F.Mask" "F.Paste")
			(solder_mask_margin 0)
			(solder_paste_margin 0)
		)
		(pad "6" smd rect
			(at 0.515 -0.4)
			(size 0.37 0.24)
			(layers "F.Cu" "F.Mask" "F.Paste")
			(net "+5.0V")
			(solder_mask_margin 0)
			(solder_paste_margin 0)
		)
		(pad "7" smd rect
			(at 0 0)
			(size 0.4 1.08)
			(layers "F.Cu" "F.Mask" "F.Paste")
			(net "GND")
			(solder_mask_margin 0)
			(solder_paste_margin 0)
		)
	)
	(footprint "Vault:FP-GRM31C-0_2-e0_3_0_8-IPC_C"
		(layer "F.Cu")
		(at 79.9216 57.6162 180)
		(property "Reference" "C12"
			(at 4.1 -0.493345 0)
			(unlocked yes)
			(layer "F.SilkS")
			(effects
				(font
					(size 0.762 0.762)
					(thickness 0.2286)
				)
				(justify left bottom)
			)
		)
		(property "Value" "4.7uF_50V_1206"
			(at -1.9013 -25.814045 0)
			(unlocked yes)
			(layer "F.SilkS")
			(hide yes)
			(effects
				(font
					(size 0.762 0.762)
					(thickness 0.2286)
				)
				(justify left bottom)
			)
		)
		(sheetname "03-POWER")
		(sheetfile "03-POWER.kicad_sch")
		(duplicate_pad_numbers_are_jumpers no)
		(fp_line
			(start 0.39847 0.9)
			(end -0.39846 0.9)
			(stroke
				(width 0.2)
				(type solid)
			)
			(layer "F.SilkS")
		)
		(fp_line
			(start 0.39847 -0.9)
			(end -0.39846 -0.9)
			(stroke
				(width 0.2)
				(type solid)
			)
			(layer "F.SilkS")
		)
		(fp_line
			(start 1.9531 1)
			(end -1.9531 1)
			(stroke
				(width 0.2)
				(type solid)
			)
			(layer "F.CrtYd")
		)
		(fp_line
			(start 1.9531 -1)
			(end 1.9531 1)
			(stroke
				(width 0.2)
				(type solid)
			)
			(layer "F.CrtYd")
		)
		(fp_line
			(start 1.9531 -1)
			(end -1.9531 -1)
			(stroke
				(width 0.2)
				(type solid)
			)
			(layer "F.CrtYd")
		)
		(fp_line
			(start -1.9531 -1)
			(end -1.9531 1)
			(stroke
				(width 0.2)
				(type solid)
			)
			(layer "F.CrtYd")
		)
		(fp_line
			(start 1.9531 1)
			(end -1.9531 1)
			(stroke
				(width 0.2)
				(type solid)
			)
			(layer "F.Fab")
		)
		(fp_line
			(start 1.9531 -1)
			(end 1.9531 1)
			(stroke
				(width 0.2)
				(type solid)
			)
			(layer "F.Fab")
		)
		(fp_line
			(start 1.9531 -1)
			(end -1.9531 -1)
			(stroke
				(width 0.2)
				(type solid)
			)
			(layer "F.Fab")
		)
		(fp_line
			(start 0.5 0)
			(end -0.5 0)
			(stroke
				(width 0.1)
				(type solid)
			)
			(layer "F.Fab")
		)
		(fp_line
			(start 0 -0.5)
			(end 0 0.5)
			(stroke
				(width 0.1)
				(type solid)
			)
			(layer "F.Fab")
		)
		(fp_line
			(start -1.9531 -1)
			(end -1.9531 1)
			(stroke
				(width 0.2)
				(type solid)
			)
			(layer "F.Fab")
		)
		(fp_text user "${REFERENCE}"
			(at -0.00001 0.09601 180)
			(unlocked yes)
			(layer "F.Fab")
			(effects
				(font
					(face "Arial")
					(size 0.63 0.63)
					(thickness 0.1)
				)
				(justify left bottom)
			)
		)
		(pad "1" smd rect
			(at -1.27578 0 180)
			(size 1.15464 1.7062)
			(layers "F.Cu" "F.Mask" "F.Paste")
			(net "+12V")
			(solder_mask_margin 0)
			(solder_paste_margin 0)
		)
		(pad "2" smd rect
			(at 1.27578 0 180)
			(size 1.15464 1.7062)
			(layers "F.Cu" "F.Mask" "F.Paste")
			(net "GND")
			(solder_mask_margin 0)
			(solder_paste_margin 0)
		)
	)
	(footprint "Vault:FP-LTST-C191KGKT-MFG"
		(layer "F.Cu")
		(at 225.2716 102.38745)
		(property "Reference" "D12"
			(at -3.90792 -0.155439 0)
			(unlocked yes)
			(layer "F.SilkS")
			(effects
				(font
					(size 0.762 0.762)
					(thickness 0.2032)
				)
			)
		)
		(property "Value" "LTST-C191KGKT"
			(at -3.494271 8.97586 270)
			(unlocked yes)
			(layer "F.SilkS")
			(hide yes)
			(effects
				(font
					(size 0.762 0.762)
					(thickness 0.2032)
				)
			)
		)
		(sheetname "08-DIPSwitches_I2C")
		(sheetfile "08-DIPSwitches_I2C.kicad_sch")
		(duplicate_pad_numbers_are_jumpers no)
		(fp_line
			(start -0.85 -0.775)
			(end 0.85 -0.775)
			(stroke
				(width 0.2)
				(type solid)
			)
			(layer "F.SilkS")
		)
		(fp_line
			(start -0.85 0.775)
			(end 0.85 0.775)
			(stroke
				(width 0.2)
				(type solid)
			)
			(layer "F.SilkS")
		)
		(fp_circle
			(center -1.7 0)
			(end -1.7 -0.125)
			(stroke
				(width 0.25)
				(type solid)
			)
			(fill no)
			(layer "F.SilkS")
		)
		(fp_line
			(start -1.25 -0.55)
			(end 1.25 -0.55)
			(stroke
				(width 0.2)
				(type solid)
			)
			(layer "F.CrtYd")
		)
		(fp_line
			(start -1.25 0.55)
			(end -1.25 -0.55)
			(stroke
				(width 0.2)
				(type solid)
			)
			(layer "F.CrtYd")
		)
		(fp_line
			(start -1.25 0.55)
			(end 1.25 0.55)
			(stroke
				(width 0.2)
				(type solid)
			)
			(layer "F.CrtYd")
		)
		(fp_line
			(start 1.25 0.55)
			(end 1.25 -0.55)
			(stroke
				(width 0.2)
				(type solid)
			)
			(layer "F.CrtYd")
		)
		(fp_line
			(start -1.25 -0.55)
			(end 1.25 -0.55)
			(stroke
				(width 0.2)
				(type solid)
			)
			(layer "F.Fab")
		)
		(fp_line
			(start -1.25 0.55)
			(end -1.25 -0.55)
			(stroke
				(width 0.2)
				(type solid)
			)
			(layer "F.Fab")
		)
		(fp_line
			(start -1.25 0.55)
			(end 1.25 0.55)
			(stroke
				(width 0.2)
				(type solid)
			)
			(layer "F.Fab")
		)
		(fp_line
			(start -0.5 0)
			(end 0.5 0)
			(stroke
				(width 0.1)
				(type solid)
			)
			(layer "F.Fab")
		)
		(fp_line
			(start 0 0.5)
			(end 0 -0.5)
			(stroke
				(width 0.1)
				(type solid)
			)
			(layer "F.Fab")
		)
		(fp_line
			(start 1.25 0.55)
			(end 1.25 -0.55)
			(stroke
				(width 0.2)
				(type solid)
			)
			(layer "F.Fab")
		)
		(fp_text user "${REFERENCE}"
			(at 0 0.29534 360)
			(unlocked yes)
			(layer "F.Fab")
			(effects
				(font
					(face "Arial")
					(size 0.63 0.63)
					(thickness 0.1)
				)
				(justify left bottom)
			)
		)
		(pad "1" smd rect
			(at -0.75 0)
			(size 0.8 0.8)
			(layers "F.Cu" "F.Mask" "F.Paste")
			(net "NetD12_1")
			(solder_mask_margin 0)
			(solder_paste_margin 0)
		)
		(pad "2" smd rect
			(at 0.75 0)
			(size 0.8 0.8)
			(layers "F.Cu" "F.Mask" "F.Paste")
			(net "+3.3V")
			(solder_mask_margin 0)
			(solder_paste_margin 0)
		)
	)
	(footprint "Vault:FP-0402-L_1_0_0_05-W_0_5-IPC_A"
		(layer "F.Cu")
		(at 162.25767 85.5662 180)
		(property "Reference" "C82"
			(at 2.00747 0.023069 0)
			(unlocked yes)
			(layer "F.SilkS")
			(effects
				(font
					(size 0.762 0.762)
					(thickness 0.2286)
				)
			)
		)
		(property "Value" "1uF_16V_0402"
			(at -2.744951 8.290315 90)
			(unlocked yes)
			(layer "F.SilkS")
			(hide yes)
			(effects
				(font
					(size 0.762 0.762)
					(thickness 0.2286)
				)
			)
		)
		(sheetname "03-POWER")
		(sheetfile "03-POWER.kicad_sch")
		(duplicate_pad_numbers_are_jumpers no)
		(fp_line
			(start 0.83623 0.73624)
			(end -0.83624 0.73624)
			(stroke
				(width 0.2)
				(type solid)
			)
			(layer "F.SilkS")
		)
		(fp_line
			(start 0.83623 -0.73624)
			(end -0.83624 -0.73624)
			(stroke
				(width 0.2)
				(type solid)
			)
			(layer "F.SilkS")
		)
		(fp_line
			(start 1.03623 0.53624)
			(end -1.03624 0.53624)
			(stroke
				(width 0.2)
				(type solid)
			)
			(layer "F.CrtYd")
		)
		(fp_line
			(start 1.03623 -0.53624)
			(end 1.03623 0.53624)
			(stroke
				(width 0.2)
				(type solid)
			)
			(layer "F.CrtYd")
		)
		(fp_line
			(start 1.03623 -0.53624)
			(end -1.03624 -0.53624)
			(stroke
				(width 0.2)
				(type solid)
			)
			(layer "F.CrtYd")
		)
		(fp_line
			(start -1.03624 -0.53624)
			(end -1.03624 0.53624)
			(stroke
				(width 0.2)
				(type solid)
			)
			(layer "F.CrtYd")
		)
		(fp_line
			(start 1.03623 0.53624)
			(end -1.03624 0.53624)
			(stroke
				(width 0.2)
				(type solid)
			)
			(layer "F.Fab")
		)
		(fp_line
			(start 1.03623 -0.53624)
			(end 1.03623 0.53624)
			(stroke
				(width 0.2)
				(type solid)
			)
			(layer "F.Fab")
		)
		(fp_line
			(start 1.03623 -0.53624)
			(end -1.03624 -0.53624)
			(stroke
				(width 0.2)
				(type solid)
			)
			(layer "F.Fab")
		)
		(fp_line
			(start 0.5 0)
			(end -0.5 0)
			(stroke
				(width 0.1)
				(type solid)
			)
			(layer "F.Fab")
		)
		(fp_line
			(start 0 -0.5)
			(end 0 0.5)
			(stroke
				(width 0.1)
				(type solid)
			)
			(layer "F.Fab")
		)
		(fp_line
			(start -1.03624 -0.53624)
			(end -1.03624 0.53624)
			(stroke
				(width 0.2)
				(type solid)
			)
			(layer "F.Fab")
		)
		(fp_text user "${REFERENCE}"
			(at -0.00001 0.09602 180)
			(unlocked yes)
			(layer "F.Fab")
			(effects
				(font
					(face "Arial")
					(size 0.63 0.63)
					(thickness 0.1)
				)
				(justify left bottom)
			)
		)
		(pad "1" smd rect
			(at -0.47856 0 180)
			(size 0.71535 0.67248)
			(layers "F.Cu" "F.Mask" "F.Paste")
			(net "+3.3V")
			(solder_mask_margin 0)
			(solder_paste_margin 0)
		)
		(pad "2" smd rect
			(at 0.47856 0 180)
			(size 0.71535 0.67248)
			(layers "F.Cu" "F.Mask" "F.Paste")
			(net "GND")
			(solder_mask_margin 0)
			(solder_paste_margin 0)
		)
	)
	(footprint "Vault:RESC1005X40X25NL05T05"
		(layer "F.Cu")
		(at 172.4216 110.8162 180)
		(property "Reference" "R126"
			(at -0.50888 1.454769 0)
			(unlocked yes)
			(layer "F.SilkS")
			(effects
				(font
					(size 0.762 0.762)
					(thickness 0.2032)
				)
			)
		)
		(property "Value" "27_1%_0402"
			(at -2.732271 7.35092 90)
			(unlocked yes)
			(layer "F.SilkS")
			(hide yes)
			(effects
				(font
					(size 0.762 0.762)
					(thickness 0.2032)
				)
			)
		)
		(sheetname "08-DIPSwitches_I2C")
		(sheetfile "08-DIPSwitches_I2C.kicad_sch")
		(duplicate_pad_numbers_are_jumpers no)
		(pad "1" smd rect
			(at -0.45 0 270)
			(size 0.55 0.55)
			(layers "F.Cu" "F.Mask" "F.Paste")
			(net "GND")
		)
		(pad "2" smd rect
			(at 0.45 0 270)
			(size 0.55 0.55)
			(layers "F.Cu" "F.Mask" "F.Paste")
			(net "NetR126_2")
		)
	)
	(footprint "SA53:SolderSocket"
		(locked yes)
		(layer "F.Cu")
		(at 119.4216 140.0162 90)
		(property "Reference" "SKT1"
			(at -3.426921 1.2286 0)
			(unlocked yes)
			(layer "F.SilkS")
			(effects
				(font
					(size 0.762 0.762)
					(thickness 0.2286)
				)
			)
		)
		(property "Value" "0332-0-43-80-18-27-10-0"
			(at -2.910071 16.1362 0)
			(unlocked yes)
			(layer "F.SilkS")
			(hide yes)
			(effects
				(font
					(size 0.762 0.762)
					(thickness 0.2286)
				)
			)
		)
		(sheetname "06-MAC")
		(sheetfile "06-MAC.kicad_sch")
		(duplicate_pad_numbers_are_jumpers no)
		(pad "1" thru_hole circle
			(at 0 0 90)
			(size 2.54 2.54)
			(drill 2.0066)
			(layers "*.Cu" "*.Mask")
			(remove_unused_layers no)
			(net "MAC_TX")
			(thermal_bridge_angle 90)
		)
	)
)
